# T6G (Grand Teton) — schematic netlist excerpt (pin names and nets, part order shuffled) for the footprints in the layout excerpt that follows; sources: Cadence DE-HDL packaged netlist, KiCad conversion of 04192023_DAF0TMB3IC0_F0TG_MB_C_brd_V02_OCP.brd

C2399  Q_CAP  22UF 4V 20% X6S  pkg C0402  page 73 : A = PVDDCR_CPU1_P1 ; B = GND
C2033  Q_CAP  0.1UF 25V 10% X7R  pkg 0402  page 234 : A = P3V3_AUX_USB_HUB ; B = GND
R845  Q_RES  4.7K 5% CHIP  pkg 0201LF  page 185 : A = RT_ROM_SMB_MUX_ADDR2 ; B = GND

(kicad_pcb
	(version 20260206)
	(generator "pcbnew")
	(generator_version "10.0")
	(general
		(thickness 1.6)
		(legacy_teardrops no)
	)
	(paper "A4")
	(title_block
		(title "04192023_DAF0TMB3IC0_F0TG_MB_C_brd_V02_OCP.brd")
		(comment 1 "Grand Teton / footprints 7205-7207 of 8354")
	)
	(layers
		(0 "F.Cu" signal "TOP")
		(4 "In1.Cu" signal "GND")
		(6 "In2.Cu" signal "IN1")
		(8 "In3.Cu" signal "GND1")
		(10 "In4.Cu" signal "IN2")
		(12 "In5.Cu" signal "GND2")
		(14 "In6.Cu" signal "IN3")
		(16 "In7.Cu" signal "GND3")
		(18 "In8.Cu" signal "VCC")
		(20 "In9.Cu" signal "VCC1")
		(22 "In10.Cu" signal "GND4")
		(24 "In11.Cu" signal "IN4")
		(26 "In12.Cu" signal "GND5")
		(28 "In13.Cu" signal "IN5")
		(30 "In14.Cu" signal "GND6")
		(32 "In15.Cu" signal "IN6")
		(34 "In16.Cu" signal "GND7")
		(2 "B.Cu" signal "BOTTOM")
		(9 "F.Adhes" user "F.Adhesive")
		(11 "B.Adhes" user "B.Adhesive")
		(13 "F.Paste" user "Package Geometry/Pastemask Top")
		(15 "B.Paste" user "Package Geometry/Pastemask Bottom")
		(5 "F.SilkS" user "Ref Des/Silkscreen Top")
		(7 "B.SilkS" user "Ref Des/Silkscreen Bottom")
		(1 "F.Mask" user "Board Geometry/Soldermask Top")
		(3 "B.Mask" user "Board Geometry/Soldermask Bottom")
		(17 "Dwgs.User" user "User.Drawings")
		(19 "Cmts.User" user "User.Comments")
		(21 "Eco1.User" user "User.Eco1")
		(23 "Eco2.User" user "User.Eco2")
		(25 "Edge.Cuts" user "Board Geometry/Outline")
		(27 "Margin" user)
		(31 "F.CrtYd" user "Package Geometry/Place Bound Top")
		(29 "B.CrtYd" user "Package Geometry/Place Bound Bottom")
		(35 "F.Fab" user "Ref Des/Assembly Top")
		(33 "B.Fab" user "Ref Des/Assembly Bottom")
	)
	(footprint ""
		(layer "B.Cu")
		(at 125.262386 -267.49883)
		(property "Reference" "C2399"
			(at 0 0 0)
			(layer "B.SilkS")
			(hide yes)
			(effects
				(font
					(size 1.27 1.27)
				)
				(justify mirror)
			)
		)
		(property "Value" ""
			(at 0 0 0)
			(layer "B.Fab")
			(effects
				(font
					(size 1.27 1.27)
				)
				(justify mirror)
			)
		)
		(duplicate_pad_numbers_are_jumpers no)
		(fp_line
			(start -0.7874 -0.4064)
			(end -0.7874 0.4064)
			(stroke
				(width 0.1524)
				(type default)
			)
			(layer "B.SilkS")
		)
		(fp_line
			(start -0.7874 0.4064)
			(end 0.7874 0.4064)
			(stroke
				(width 0.1524)
				(type default)
			)
			(layer "B.SilkS")
		)
		(fp_line
			(start 0.7874 -0.4064)
			(end -0.7874 -0.4064)
			(stroke
				(width 0.1524)
				(type default)
			)
			(layer "B.SilkS")
		)
		(fp_line
			(start 0.7874 0.4064)
			(end 0.7874 -0.4064)
			(stroke
				(width 0.1524)
				(type default)
			)
			(layer "B.SilkS")
		)
		(fp_line
			(start -0.67945 -0.3048)
			(end -0.67945 0.3048)
			(stroke
				(width 0.1)
				(type default)
			)
			(layer "B.Fab")
		)
		(fp_line
			(start -0.67945 0.3048)
			(end -0.120396 0.3048)
			(stroke
				(width 0.1)
				(type default)
			)
			(layer "B.Fab")
		)
		(fp_line
			(start -0.12065 -0.3048)
			(end -0.67945 -0.3048)
			(stroke
				(width 0.1)
				(type default)
			)
			(layer "B.Fab")
		)
		(fp_line
			(start -0.12065 -0.2794)
			(end -0.12065 -0.3048)
			(stroke
				(width 0.1)
				(type default)
			)
			(layer "B.Fab")
		)
		(fp_line
			(start -0.120396 0.2794)
			(end 0.12065 0.2794)
			(stroke
				(width 0.1)
				(type default)
			)
			(layer "B.Fab")
		)
		(fp_line
			(start -0.120396 0.3048)
			(end -0.120396 0.2794)
			(stroke
				(width 0.1)
				(type default)
			)
			(layer "B.Fab")
		)
		(fp_line
			(start 0.12065 -0.305054)
			(end 0.12065 -0.2794)
			(stroke
				(width 0.1)
				(type default)
			)
			(layer "B.Fab")
		)
		(fp_line
			(start 0.12065 -0.2794)
			(end -0.12065 -0.2794)
			(stroke
				(width 0.1)
				(type default)
			)
			(layer "B.Fab")
		)
		(fp_line
			(start 0.12065 0.2794)
			(end 0.12065 0.3048)
			(stroke
				(width 0.1)
				(type default)
			)
			(layer "B.Fab")
		)
		(fp_line
			(start 0.12065 0.3048)
			(end 0.67945 0.3048)
			(stroke
				(width 0.1)
				(type default)
			)
			(layer "B.Fab")
		)
		(fp_line
			(start 0.67945 -0.305054)
			(end 0.12065 -0.305054)
			(stroke
				(width 0.1)
				(type default)
			)
			(layer "B.Fab")
		)
		(fp_line
			(start 0.67945 0.3048)
			(end 0.67945 -0.305054)
			(stroke
				(width 0.1)
				(type default)
			)
			(layer "B.Fab")
		)
		(pad "1" smd circle
			(at 0.40005 0 180)
			(size 0 0)
			(layers "B.Cu" "B.Mask" "B.Paste")
			(net "PVDDCR_CPU1_P1")
		)
		(pad "2" smd circle
			(at -0.40005 0 180)
			(size 0 0)
			(layers "B.Cu" "B.Mask" "B.Paste")
			(net "GND")
		)
	)
	(footprint ""
		(layer "B.Cu")
		(at 255.905 -332.867 180)
		(property "Reference" "R845"
			(at 0 0 0)
			(layer "B.SilkS")
			(hide yes)
			(effects
				(font
					(size 1.27 1.27)
				)
				(justify mirror)
			)
		)
		(property "Value" ""
			(at 0 0 0)
			(layer "B.Fab")
			(effects
				(font
					(size 1.27 1.27)
				)
				(justify mirror)
			)
		)
		(duplicate_pad_numbers_are_jumpers no)
		(fp_line
			(start 0.32512 0.175006)
			(end 0.32512 -0.175006)
			(stroke
				(width 0.1)
				(type default)
			)
			(layer "B.Fab")
		)
		(fp_line
			(start 0.32512 -0.175006)
			(end -0.32512 -0.175006)
			(stroke
				(width 0.1)
				(type default)
			)
			(layer "B.Fab")
		)
		(fp_line
			(start -0.32512 0.175006)
			(end 0.32512 0.175006)
			(stroke
				(width 0.1)
				(type default)
			)
			(layer "B.Fab")
		)
		(fp_line
			(start -0.32512 -0.175006)
			(end -0.32512 0.175006)
			(stroke
				(width 0.1)
				(type default)
			)
			(layer "B.Fab")
		)
		(pad "1" smd rect
			(at 0.2667 0)
			(size 0.3048 0.381)
			(layers "B.Cu" "B.Mask" "B.Paste")
			(net "RT_ROM_SMB_MUX_ADDR2")
		)
		(pad "2" smd rect
			(at -0.2667 0 180)
			(size 0.3048 0.381)
			(layers "B.Cu" "B.Mask" "B.Paste")
			(net "GND")
		)
	)
	(footprint ""
		(layer "B.Cu")
		(at 12.003532 -99.925632 180)
		(property "Reference" "C2033"
			(at 0 0 0)
			(layer "B.SilkS")
			(hide yes)
			(effects
				(font
					(size 1.27 1.27)
				)
				(justify mirror)
			)
		)
		(property "Value" ""
			(at 0 0 0)
			(layer "B.Fab")
			(effects
				(font
					(size 1.27 1.27)
				)
				(justify mirror)
			)
		)
		(duplicate_pad_numbers_are_jumpers no)
		(fp_line
			(start 0.7874 0.4064)
			(end 0.7874 -0.4064)
			(stroke
				(width 0.1524)
				(type default)
			)
			(layer "B.SilkS")
		)
		(fp_line
			(start 0.7874 -0.4064)
			(end -0.7874 -0.4064)
			(stroke
				(width 0.1524)
				(type default)
			)
			(layer "B.SilkS")
		)
		(fp_line
			(start -0.7874 0.4064)
			(end 0.7874 0.4064)
			(stroke
				(width 0.1524)
				(type default)
			)
			(layer "B.SilkS")
		)
		(fp_line
			(start -0.7874 -0.4064)
			(end -0.7874 0.4064)
			(stroke
				(width 0.1524)
				(type default)
			)
			(layer "B.SilkS")
		)
		(fp_line
			(start 0.67945 0.3048)
			(end 0.67945 -0.305054)
			(stroke
				(width 0.1)
				(type default)
			)
			(layer "B.Fab")
		)
		(fp_line
			(start 0.67945 -0.305054)
			(end 0.12065 -0.305054)
			(stroke
				(width 0.1)
				(type default)
			)
			(layer "B.Fab")
		)
		(fp_line
			(start 0.12065 0.3048)
			(end 0.67945 0.3048)
			(stroke
				(width 0.1)
				(type default)
			)
			(layer "B.Fab")
		)
		(fp_line
			(start 0.12065 0.2794)
			(end 0.12065 0.3048)
			(stroke
				(width 0.1)
				(type default)
			)
			(layer "B.Fab")
		)
		(fp_line
			(start 0.12065 -0.2794)
			(end -0.12065 -0.2794)
			(stroke
				(width 0.1)
				(type default)
			)
			(layer "B.Fab")
		)
		(fp_line
			(start 0.12065 -0.305054)
			(end 0.12065 -0.2794)
			(stroke
				(width 0.1)
				(type default)
			)
			(layer "B.Fab")
		)
		(fp_line
			(start -0.120396 0.3048)
			(end -0.120396 0.2794)
			(stroke
				(width 0.1)
				(type default)
			)
			(layer "B.Fab")
		)
		(fp_line
			(start -0.120396 0.2794)
			(end 0.12065 0.2794)
			(stroke
				(width 0.1)
				(type default)
			)
			(layer "B.Fab")
		)
		(fp_line
			(start -0.12065 -0.2794)
			(end -0.12065 -0.3048)
			(stroke
				(width 0.1)
				(type default)
			)
			(layer "B.Fab")
		)
		(fp_line
			(start -0.12065 -0.3048)
			(end -0.67945 -0.3048)
			(stroke
				(width 0.1)
				(type default)
			)
			(layer "B.Fab")
		)
		(fp_line
			(start -0.67945 0.3048)
			(end -0.120396 0.3048)
			(stroke
				(width 0.1)
				(type default)
			)
			(layer "B.Fab")
		)
		(fp_line
			(start -0.67945 -0.3048)
			(end -0.67945 0.3048)
			(stroke
				(width 0.1)
				(type default)
			)
			(layer "B.Fab")
		)
		(pad "1" smd circle
			(at 0.40005 0)
			(size 0 0)
			(layers "B.Cu" "B.Mask" "B.Paste")
			(net "P3V3_AUX_USB_HUB")
		)
		(pad "2" smd circle
			(at -0.40005 0)
			(size 0 0)
			(layers "B.Cu" "B.Mask" "B.Paste")
			(net "GND")
		)
	)
)
